# S9S_MB_2U (Grand Teton) — schematic netlist excerpt (pin names and nets, part order shuffled) for the footprints in the layout excerpt that follows; sources: Cadence DE-HDL packaged netlist, KiCad conversion of 03242023_DA0F0TMBIJ0_F0T_Motherboard_J_brd_V01_OCP.brd

PC1268  Q_CAP  22UF 4V 20% X6S  pkg C0805  page 299 : A = PVPP_HBM_CPU1 ; B = GND
PR3980  Q_RES  0 5% CHIP  pkg 0402LF  page 303 : A = HSC_VDD_R_3 ; B = HSC_VDD
R4468  Q_RES  0 5% CHIP  pkg 0402LF  page 196 : A = USB2_HUB_2_BUF_EXT_R_DN ; B = USB2_HUB_2_BUF_EXT_DN

(kicad_pcb
	(version 20260206)
	(generator "pcbnew")
	(generator_version "10.0")
	(general
		(thickness 1.6)
		(legacy_teardrops no)
	)
	(paper "A4")
	(title_block
		(title "03242023_DA0F0TMBIJ0_F0T_Motherboard_J_brd_V01_OCP.brd")
		(comment 1 "Grand Teton / footprints 6075-6077 of 6105")
	)
	(layers
		(0 "F.Cu" signal "TOP")
		(4 "In1.Cu" signal "GND")
		(6 "In2.Cu" signal "IN1")
		(8 "In3.Cu" signal "GND1")
		(10 "In4.Cu" signal "IN2")
		(12 "In5.Cu" signal "GND2")
		(14 "In6.Cu" signal "IN3")
		(16 "In7.Cu" signal "GND3")
		(18 "In8.Cu" signal "VCC")
		(20 "In9.Cu" signal "VCC1")
		(22 "In10.Cu" signal "GND4")
		(24 "In11.Cu" signal "IN4")
		(26 "In12.Cu" signal "GND5")
		(28 "In13.Cu" signal "IN5")
		(30 "In14.Cu" signal "GND6")
		(32 "In15.Cu" signal "IN6")
		(34 "In16.Cu" signal "GND7")
		(2 "B.Cu" signal "BOTTOM")
		(9 "F.Adhes" user "F.Adhesive")
		(11 "B.Adhes" user "B.Adhesive")
		(13 "F.Paste" user "Package Geometry/Pastemask Top")
		(15 "B.Paste" user "Package Geometry/Pastemask Bottom")
		(5 "F.SilkS" user "Ref Des/Silkscreen Top")
		(7 "B.SilkS" user "Ref Des/Silkscreen Bottom")
		(1 "F.Mask" user "Board Geometry/Soldermask Top")
		(3 "B.Mask" user "Board Geometry/Soldermask Bottom")
		(17 "Dwgs.User" user "User.Drawings")
		(19 "Cmts.User" user "User.Comments")
		(21 "Eco1.User" user "User.Eco1")
		(23 "Eco2.User" user "User.Eco2")
		(25 "Edge.Cuts" user "Board Geometry/Outline")
		(27 "Margin" user)
		(31 "F.CrtYd" user "Package Geometry/Place Bound Top")
		(29 "B.CrtYd" user "Package Geometry/Place Bound Bottom")
		(35 "F.Fab" user "Ref Des/Assembly Top")
		(33 "B.Fab" user "Ref Des/Assembly Bottom")
	)
	(footprint ""
		(layer "B.Cu")
		(at 123.640342 -366.723168 90)
		(property "Reference" "PC1268"
			(at 0 0 90)
			(layer "B.SilkS")
			(hide yes)
			(effects
				(font
					(size 1.27 1.27)
				)
				(justify mirror)
			)
		)
		(property "Value" ""
			(at 0 0 90)
			(layer "B.Fab")
			(effects
				(font
					(size 1.27 1.27)
				)
				(justify mirror)
			)
		)
		(duplicate_pad_numbers_are_jumpers no)
		(fp_line
			(start 1.524 -0.762)
			(end -1.524 -0.762)
			(stroke
				(width 0.1524)
				(type default)
			)
			(layer "B.SilkS")
		)
		(fp_line
			(start -1.524 -0.762)
			(end -1.524 0.762)
			(stroke
				(width 0.1524)
				(type default)
			)
			(layer "B.SilkS")
		)
		(fp_line
			(start 1.524 0.762)
			(end 1.524 -0.762)
			(stroke
				(width 0.1524)
				(type default)
			)
			(layer "B.SilkS")
		)
		(fp_line
			(start -1.524 0.762)
			(end 1.524 0.762)
			(stroke
				(width 0.1524)
				(type default)
			)
			(layer "B.SilkS")
		)
		(fp_line
			(start 1.1049 -0.724916)
			(end 1.1049 0.724916)
			(stroke
				(width 0.1)
				(type default)
			)
			(layer "B.Fab")
		)
		(fp_line
			(start -1.1049 -0.724916)
			(end 1.1049 -0.724916)
			(stroke
				(width 0.1)
				(type default)
			)
			(layer "B.Fab")
		)
		(fp_line
			(start 1.1049 0.724916)
			(end -1.1049 0.724916)
			(stroke
				(width 0.1)
				(type default)
			)
			(layer "B.Fab")
		)
		(fp_line
			(start -1.1049 0.724916)
			(end -1.1049 -0.724916)
			(stroke
				(width 0.1)
				(type default)
			)
			(layer "B.Fab")
		)
		(pad "1" smd rect
			(at 0.889 0 90)
			(size 1.016 1.27)
			(layers "B.Cu" "B.Mask" "B.Paste")
			(net "PVPP_HBM_CPU1")
		)
		(pad "2" smd rect
			(at -0.889 0 90)
			(size 1.016 1.27)
			(layers "B.Cu" "B.Mask" "B.Paste")
			(net "GND")
		)
	)
	(footprint ""
		(layer "B.Cu")
		(at 137.50798 -22.943058 90)
		(property "Reference" "R4468"
			(at 0 0 90)
			(layer "B.SilkS")
			(hide yes)
			(effects
				(font
					(size 1.27 1.27)
				)
				(justify mirror)
			)
		)
		(property "Value" ""
			(at 0 0 90)
			(layer "B.Fab")
			(effects
				(font
					(size 1.27 1.27)
				)
				(justify mirror)
			)
		)
		(duplicate_pad_numbers_are_jumpers no)
		(fp_line
			(start 0.7874 -0.4064)
			(end -0.7874 -0.4064)
			(stroke
				(width 0.1524)
				(type default)
			)
			(layer "B.SilkS")
		)
		(fp_line
			(start -0.7874 -0.4064)
			(end -0.7874 0.00762)
			(stroke
				(width 0.1524)
				(type default)
			)
			(layer "B.SilkS")
		)
		(fp_line
			(start 0.7874 0.02794)
			(end 0.7874 -0.4064)
			(stroke
				(width 0.1524)
				(type default)
			)
			(layer "B.SilkS")
		)
		(fp_line
			(start -0.41275 0.4064)
			(end 0.44323 0.4064)
			(stroke
				(width 0.1524)
				(type default)
			)
			(layer "B.SilkS")
		)
		(fp_line
			(start 0.67945 -0.305054)
			(end 0.12065 -0.305054)
			(stroke
				(width 0.1)
				(type default)
			)
			(layer "B.Fab")
		)
		(fp_line
			(start 0.12065 -0.305054)
			(end 0.12065 -0.2794)
			(stroke
				(width 0.1)
				(type default)
			)
			(layer "B.Fab")
		)
		(fp_line
			(start -0.12065 -0.3048)
			(end -0.67945 -0.3048)
			(stroke
				(width 0.1)
				(type default)
			)
			(layer "B.Fab")
		)
		(fp_line
			(start -0.67945 -0.3048)
			(end -0.67945 0.3048)
			(stroke
				(width 0.1)
				(type default)
			)
			(layer "B.Fab")
		)
		(fp_line
			(start 0.12065 -0.2794)
			(end -0.12065 -0.2794)
			(stroke
				(width 0.1)
				(type default)
			)
			(layer "B.Fab")
		)
		(fp_line
			(start -0.12065 -0.2794)
			(end -0.12065 -0.3048)
			(stroke
				(width 0.1)
				(type default)
			)
			(layer "B.Fab")
		)
		(fp_line
			(start 0.12065 0.2794)
			(end 0.12065 0.3048)
			(stroke
				(width 0.1)
				(type default)
			)
			(layer "B.Fab")
		)
		(fp_line
			(start -0.120396 0.2794)
			(end 0.12065 0.2794)
			(stroke
				(width 0.1)
				(type default)
			)
			(layer "B.Fab")
		)
		(fp_line
			(start 0.67945 0.3048)
			(end 0.67945 -0.305054)
			(stroke
				(width 0.1)
				(type default)
			)
			(layer "B.Fab")
		)
		(fp_line
			(start 0.12065 0.3048)
			(end 0.67945 0.3048)
			(stroke
				(width 0.1)
				(type default)
			)
			(layer "B.Fab")
		)
		(fp_line
			(start -0.120396 0.3048)
			(end -0.120396 0.2794)
			(stroke
				(width 0.1)
				(type default)
			)
			(layer "B.Fab")
		)
		(fp_line
			(start -0.67945 0.3048)
			(end -0.120396 0.3048)
			(stroke
				(width 0.1)
				(type default)
			)
			(layer "B.Fab")
		)
		(pad "1" smd circle
			(at 0.40005 0 270)
			(size 0 0)
			(layers "B.Cu" "B.Mask" "B.Paste")
			(net "USB2_HUB_2_BUF_EXT_R_DN")
		)
		(pad "2" smd circle
			(at -0.40005 0 270)
			(size 0 0)
			(layers "B.Cu" "B.Mask" "B.Paste")
			(net "USB2_HUB_2_BUF_EXT_DN")
		)
	)
	(footprint ""
		(layer "B.Cu")
		(at 216.00541 -403.668738 -90)
		(property "Reference" "PR3980"
			(at 0 0 90)
			(layer "B.SilkS")
			(hide yes)
			(effects
				(font
					(size 1.27 1.27)
				)
				(justify mirror)
			)
		)
		(property "Value" ""
			(at 0 0 90)
			(layer "B.Fab")
			(effects
				(font
					(size 1.27 1.27)
				)
				(justify mirror)
			)
		)
		(duplicate_pad_numbers_are_jumpers no)
		(fp_line
			(start -0.7874 0.4064)
			(end 0.7874 0.4064)
			(stroke
				(width 0.1524)
				(type default)
			)
			(layer "B.SilkS")
		)
		(fp_line
			(start 0.7874 0.4064)
			(end 0.7874 -0.4064)
			(stroke
				(width 0.1524)
				(type default)
			)
			(layer "B.SilkS")
		)
		(fp_line
			(start -0.7874 -0.4064)
			(end -0.7874 0.4064)
			(stroke
				(width 0.1524)
				(type default)
			)
			(layer "B.SilkS")
		)
		(fp_line
			(start 0.7874 -0.4064)
			(end -0.7874 -0.4064)
			(stroke
				(width 0.1524)
				(type default)
			)
			(layer "B.SilkS")
		)
		(fp_line
			(start -0.67945 0.3048)
			(end -0.120396 0.3048)
			(stroke
				(width 0.1)
				(type default)
			)
			(layer "B.Fab")
		)
		(fp_line
			(start -0.120396 0.3048)
			(end -0.120396 0.2794)
			(stroke
				(width 0.1)
				(type default)
			)
			(layer "B.Fab")
		)
		(fp_line
			(start 0.12065 0.3048)
			(end 0.67945 0.3048)
			(stroke
				(width 0.1)
				(type default)
			)
			(layer "B.Fab")
		)
		(fp_line
			(start 0.67945 0.3048)
			(end 0.67945 -0.305054)
			(stroke
				(width 0.1)
				(type default)
			)
			(layer "B.Fab")
		)
		(fp_line
			(start -0.120396 0.2794)
			(end 0.12065 0.2794)
			(stroke
				(width 0.1)
				(type default)
			)
			(layer "B.Fab")
		)
		(fp_line
			(start 0.12065 0.2794)
			(end 0.12065 0.3048)
			(stroke
				(width 0.1)
				(type default)
			)
			(layer "B.Fab")
		)
		(fp_line
			(start -0.12065 -0.2794)
			(end -0.12065 -0.3048)
			(stroke
				(width 0.1)
				(type default)
			)
			(layer "B.Fab")
		)
		(fp_line
			(start 0.12065 -0.2794)
			(end -0.12065 -0.2794)
			(stroke
				(width 0.1)
				(type default)
			)
			(layer "B.Fab")
		)
		(fp_line
			(start -0.67945 -0.3048)
			(end -0.67945 0.3048)
			(stroke
				(width 0.1)
				(type default)
			)
			(layer "B.Fab")
		)
		(fp_line
			(start -0.12065 -0.3048)
			(end -0.67945 -0.3048)
			(stroke
				(width 0.1)
				(type default)
			)
			(layer "B.Fab")
		)
		(fp_line
			(start 0.12065 -0.305054)
			(end 0.12065 -0.2794)
			(stroke
				(width 0.1)
				(type default)
			)
			(layer "B.Fab")
		)
		(fp_line
			(start 0.67945 -0.305054)
			(end 0.12065 -0.305054)
			(stroke
				(width 0.1)
				(type default)
			)
			(layer "B.Fab")
		)
		(pad "1" smd circle
			(at 0.40005 0 90)
			(size 0 0)
			(layers "B.Cu" "B.Mask" "B.Paste")
			(net "HSC_VDD_R_3")
		)
		(pad "2" smd circle
			(at -0.40005 0 90)
			(size 0 0)
			(layers "B.Cu" "B.Mask" "B.Paste")
			(net "HSC_VDD")
		)
	)
)
